(kicad_pcb
	(version 20260206)
	(generator "pcbnew")
	(generator_version "10.0")
	(general
		(thickness 1.6)
		(legacy_teardrops no)
	)
	(paper "A4")
	(title_block
		(title "peb — Lightning_PEB_BRD.brd")
		(comment 1 "Lightning (Wiwynn / Facebook NVMe JBOF) / footprints 42-49 of 2563")
	)
	(layers
		(0 "F.Cu" signal "TOP")
		(4 "In1.Cu" signal "L2GND")
		(6 "In2.Cu" signal "L3")
		(8 "In3.Cu" signal "L4VCC")
		(10 "In4.Cu" signal "L5VCC")
		(12 "In5.Cu" signal "L6")
		(14 "In6.Cu" signal "L7GND")
		(2 "B.Cu" signal "BOTTOM")
		(9 "F.Adhes" user "F.Adhesive")
		(11 "B.Adhes" user "B.Adhesive")
		(13 "F.Paste" user "Package Geometry/Pastemask Top")
		(15 "B.Paste" user "Package Geometry/Pastemask Bottom")
		(5 "F.SilkS" user "Ref Des/Silkscreen Top")
		(7 "B.SilkS" user "Ref Des/Silkscreen Bottom")
		(1 "F.Mask" user "Board Geometry/Soldermask Top")
		(3 "B.Mask" user "Board Geometry/Soldermask Bottom")
		(17 "Dwgs.User" user "User.Drawings")
		(19 "Cmts.User" user "User.Comments")
		(21 "Eco1.User" user "User.Eco1")
		(23 "Eco2.User" user "User.Eco2")
		(25 "Edge.Cuts" user "Board Geometry/Outline")
		(27 "Margin" user)
		(31 "F.CrtYd" user "Package Geometry/Place Bound Top")
		(29 "B.CrtYd" user "Package Geometry/Place Bound Bottom")
		(35 "F.Fab" user "Ref Des/Assembly Top")
		(33 "B.Fab" user "Ref Des/Assembly Bottom")
	)
	(footprint ""
		(layer "F.Cu")
		(at 64.135 -43.668188 90)
		(property "Reference" "PC25"
			(at 0 0 90)
			(layer "F.SilkS")
			(hide yes)
			(effects
				(font
					(size 1.27 1.27)
				)
			)
		)
		(property "Value" "SC10U25V5KX-GP"
			(at -0.0762 -6.1214 90)
			(unlocked yes)
			(layer "F.Fab")
			(hide yes)
			(effects
				(font
					(size 1.016 1.016)
					(thickness 0.1524)
				)
			)
		)
		(property "Device Type" "C805H56"
			(at -0.0762 -8.1534 90)
			(unlocked yes)
			(layer "F.Fab")
			(hide yes)
			(effects
				(font
					(size 1.016 1.016)
					(thickness 0.1524)
				)
			)
		)
		(duplicate_pad_numbers_are_jumpers no)
		(fp_line
			(start 0.635 0)
			(end -0.635 0)
			(stroke
				(width 0.508)
				(type default)
			)
			(layer "F.SilkS")
		)
		(fp_rect
			(start -0.9652 1.778)
			(end 0.9652 -1.778)
			(stroke
				(width 0)
				(type default)
			)
			(fill no)
			(layer "F.CrtYd")
		)
		(fp_poly
			(pts
				(xy -0.9652 -1.778) (xy 0.9652 -1.778) (xy 0.9652 1.778) (xy -0.9652 1.778)
			)
			(stroke
				(width 0)
				(type default)
			)
			(fill no)
			(layer "F.Fab")
		)
		(pad "1" smd rect
			(at 0 -0.9652 90)
			(size 1.397 1.143)
			(layers "F.Cu" "F.Mask" "F.Paste")
			(net "P3V3_STBY_VIN")
		)
		(pad "2" smd rect
			(at 0 0.9652 90)
			(size 1.397 1.143)
			(layers "F.Cu" "F.Mask" "F.Paste")
			(net "GND")
		)
	)
	(footprint ""
		(layer "F.Cu")
		(at 192.659 -11.303 90)
		(property "Reference" "Q9"
			(at 0 0 90)
			(layer "F.SilkS")
			(hide yes)
			(effects
				(font
					(size 1.27 1.27)
				)
			)
		)
		(property "Value" "2N7002K-1-GP"
			(at 0.127 -8.9662 90)
			(unlocked yes)
			(layer "F.Fab")
			(hide yes)
			(effects
				(font
					(size 1.016 1.016)
					(thickness 0.1524)
				)
			)
		)
		(property "Device Type" "SOT23DGS2D4H44"
			(at 0.127 -10.4902 90)
			(unlocked yes)
			(layer "F.Fab")
			(hide yes)
			(effects
				(font
					(size 1.016 1.016)
					(thickness 0.1524)
				)
			)
		)
		(duplicate_pad_numbers_are_jumpers no)
		(fp_line
			(start 1.651 -1.778)
			(end -1.651 -1.778)
			(stroke
				(width 0.1524)
				(type default)
			)
			(layer "F.SilkS")
		)
		(fp_line
			(start -1.651 -1.778)
			(end -1.651 1.778)
			(stroke
				(width 0.1524)
				(type default)
			)
			(layer "F.SilkS")
		)
		(fp_line
			(start 1.651 1.778)
			(end 1.651 -1.778)
			(stroke
				(width 0.1524)
				(type default)
			)
			(layer "F.SilkS")
		)
		(fp_line
			(start -1.651 1.778)
			(end 1.651 1.778)
			(stroke
				(width 0.1524)
				(type default)
			)
			(layer "F.SilkS")
		)
		(fp_poly
			(pts
				(xy -1.778 1.8796) (xy -1.778 -1.8796) (xy 1.778 -1.8796) (xy 1.778 1.8796)
			)
			(stroke
				(width 0)
				(type default)
			)
			(fill no)
			(layer "F.CrtYd")
		)
		(fp_poly
			(pts
				(xy -1.778 1.8796) (xy -1.778 -1.8796) (xy 1.778 -1.8796) (xy 1.778 1.8796)
			)
			(stroke
				(width 0)
				(type default)
			)
			(fill no)
			(layer "F.Fab")
		)
		(pad "D" smd custom
			(at 0 -0.9525 90)
			(size 0.1905 0.1905)
			(layers "F.Cu" "F.Mask" "F.Paste")
			(net "ENCLO_LED_RED_D")
			(options
				(clearance outline)
				(anchor circle)
			)
			(primitives
				(gr_poly
					(pts
						(arc
							(start -0.1778 0.5715)
							(mid -0.321484 0.511984)
							(end -0.381 0.3683)
						)
						(arc
							(start -0.381 -0.3683)
							(mid -0.321484 -0.511984)
							(end -0.1778 -0.5715)
						)
						(arc
							(start 0.1778 -0.5715)
							(mid 0.321484 -0.511984)
							(end 0.381 -0.3683)
						)
						(arc
							(start 0.381 0.3683)
							(mid 0.321484 0.511984)
							(end 0.1778 0.5715)
						)
					)
					(width 0)
					(fill yes)
				)
			)
		)
		(pad "G" smd custom
			(at -0.98425 0.9525 90)
			(size 0.1905 0.1905)
			(layers "F.Cu" "F.Mask" "F.Paste")
			(net "ENCLO_LED_RED_G")
			(options
				(clearance outline)
				(anchor circle)
			)
			(primitives
				(gr_poly
					(pts
						(arc
							(start -0.1778 0.5715)
							(mid -0.321484 0.511984)
							(end -0.381 0.3683)
						)
						(arc
							(start -0.381 -0.3683)
							(mid -0.321484 -0.511984)
							(end -0.1778 -0.5715)
						)
						(arc
							(start 0.1778 -0.5715)
							(mid 0.321484 -0.511984)
							(end 0.381 -0.3683)
						)
						(arc
							(start 0.381 0.3683)
							(mid 0.321484 0.511984)
							(end 0.1778 0.5715)
						)
					)
					(width 0)
					(fill yes)
				)
			)
		)
		(pad "S" smd custom
			(at 0.98425 0.9525 90)
			(size 0.1905 0.1905)
			(layers "F.Cu" "F.Mask" "F.Paste")
			(net "GND")
			(options
				(clearance outline)
				(anchor circle)
			)
			(primitives
				(gr_poly
					(pts
						(arc
							(start -0.1778 0.5715)
							(mid -0.321484 0.511984)
							(end -0.381 0.3683)
						)
						(arc
							(start -0.381 -0.3683)
							(mid -0.321484 -0.511984)
							(end -0.1778 -0.5715)
						)
						(arc
							(start 0.1778 -0.5715)
							(mid 0.321484 -0.511984)
							(end 0.381 -0.3683)
						)
						(arc
							(start 0.381 0.3683)
							(mid 0.321484 0.511984)
							(end 0.1778 0.5715)
						)
					)
					(width 0)
					(fill yes)
				)
			)
		)
	)
	(footprint ""
		(layer "F.Cu")
		(at 235.966 -23.241)
		(property "Reference" "R812"
			(at 0 0 0)
			(layer "F.SilkS")
			(hide yes)
			(effects
				(font
					(size 1.27 1.27)
				)
			)
		)
		(property "Value" "4K7R2F-GP"
			(at 0.064008 -3.993896 0)
			(unlocked yes)
			(layer "F.Fab")
			(hide yes)
			(effects
				(font
					(size 1.016 1.016)
					(thickness 0.1524)
				)
			)
		)
		(property "Device Type" "R402H16"
			(at 0.064008 -5.517896 0)
			(unlocked yes)
			(layer "F.Fab")
			(hide yes)
			(effects
				(font
					(size 1.016 1.016)
					(thickness 0.1524)
				)
			)
		)
		(duplicate_pad_numbers_are_jumpers no)
		(fp_line
			(start -0.508 -0.9398)
			(end -0.508 0.9398)
			(stroke
				(width 0.1524)
				(type default)
			)
			(layer "F.SilkS")
		)
		(fp_line
			(start 0.508 -0.9398)
			(end -0.508 -0.9398)
			(stroke
				(width 0.1524)
				(type default)
			)
			(layer "F.SilkS")
		)
		(fp_rect
			(start -0.508 0.9398)
			(end 0.508 -0.9398)
			(stroke
				(width 0)
				(type default)
			)
			(fill no)
			(layer "F.CrtYd")
		)
		(fp_rect
			(start -0.508 0.9398)
			(end 0.508 -0.9398)
			(stroke
				(width 0)
				(type default)
			)
			(fill no)
			(layer "F.Fab")
		)
		(pad "1" smd custom
			(at 0 -0.4445)
			(size 0.1397 0.1397)
			(layers "F.Cu" "F.Mask" "F.Paste")
			(net "GND")
			(options
				(clearance outline)
				(anchor circle)
			)
			(primitives
				(gr_poly
					(pts
						(arc
							(start -0.1778 -0.2794)
							(mid -0.249642 -0.249642)
							(end -0.2794 -0.1778)
						)
						(arc
							(start -0.2794 0.1778)
							(mid -0.249642 0.249642)
							(end -0.1778 0.2794)
						)
						(arc
							(start 0.1778 0.2794)
							(mid 0.249642 0.249642)
							(end 0.2794 0.1778)
						)
						(arc
							(start 0.2794 -0.1778)
							(mid 0.249642 -0.249642)
							(end 0.1778 -0.2794)
						)
					)
					(width 0)
					(fill yes)
				)
			)
		)
		(pad "2" smd custom
			(at 0 0.4445)
			(size 0.1397 0.1397)
			(layers "F.Cu" "F.Mask" "F.Paste")
			(net "BOOTSTRAP6")
			(options
				(clearance outline)
				(anchor circle)
			)
			(primitives
				(gr_poly
					(pts
						(arc
							(start -0.1778 -0.2794)
							(mid -0.249642 -0.249642)
							(end -0.2794 -0.1778)
						)
						(arc
							(start -0.2794 0.1778)
							(mid -0.249642 0.249642)
							(end -0.1778 0.2794)
						)
						(arc
							(start 0.1778 0.2794)
							(mid 0.249642 0.249642)
							(end 0.2794 0.1778)
						)
						(arc
							(start 0.2794 -0.1778)
							(mid 0.249642 -0.249642)
							(end 0.1778 -0.2794)
						)
					)
					(width 0)
					(fill yes)
				)
			)
		)
	)
	(footprint ""
		(layer "F.Cu")
		(at 212.792056 -212.420454 180)
		(property "Reference" "C111"
			(at 0 0 180)
			(layer "F.SilkS")
			(hide yes)
			(effects
				(font
					(size 1.27 1.27)
				)
			)
		)
		(property "Value" "SCD22U10V2KX-1GP"
			(at 1.1811 -2.7051 180)
			(unlocked yes)
			(layer "F.Fab")
			(hide yes)
			(effects
				(font
					(size 1.016 1.016)
					(thickness 0.1524)
				)
			)
		)
		(property "Device Type" "C402H22"
			(at 1.1811 -4.2291 180)
			(unlocked yes)
			(layer "F.Fab")
			(hide yes)
			(effects
				(font
					(size 1.016 1.016)
					(thickness 0.1524)
				)
			)
		)
		(duplicate_pad_numbers_are_jumpers no)
		(fp_rect
			(start -0.4318 0.9525)
			(end 0.4318 -0.9525)
			(stroke
				(width 0)
				(type default)
			)
			(fill no)
			(layer "F.CrtYd")
		)
		(fp_rect
			(start -0.4318 0.9525)
			(end 0.4318 -0.9525)
			(stroke
				(width 0)
				(type default)
			)
			(fill no)
			(layer "F.Fab")
		)
		(pad "1" smd custom
			(at 0 -0.4445 180)
			(size 0.1524 0.1524)
			(layers "F.Cu" "F.Mask" "F.Paste")
			(net "PCIE_TX_CAP_P39")
			(options
				(clearance outline)
				(anchor circle)
			)
			(primitives
				(gr_poly
					(pts
						(arc
							(start 0.3048 -0.2032)
							(mid 0.275042 -0.275042)
							(end 0.2032 -0.3048)
						)
						(arc
							(start -0.2032 -0.3048)
							(mid -0.275042 -0.275042)
							(end -0.3048 -0.2032)
						)
						(arc
							(start -0.3048 0.2032)
							(mid -0.275042 0.275042)
							(end -0.2032 0.3048)
						)
						(arc
							(start 0.2032 0.3048)
							(mid 0.275042 0.275042)
							(end 0.3048 0.2032)
						)
					)
					(width 0)
					(fill yes)
				)
			)
		)
		(pad "2" smd custom
			(at 0 0.4445 180)
			(size 0.1524 0.1524)
			(layers "F.Cu" "F.Mask" "F.Paste")
			(net "PCIE_TX_P39")
			(options
				(clearance outline)
				(anchor circle)
			)
			(primitives
				(gr_poly
					(pts
						(arc
							(start 0.3048 -0.2032)
							(mid 0.275042 -0.275042)
							(end 0.2032 -0.3048)
						)
						(arc
							(start -0.2032 -0.3048)
							(mid -0.275042 -0.275042)
							(end -0.3048 -0.2032)
						)
						(arc
							(start -0.3048 0.2032)
							(mid -0.275042 0.275042)
							(end -0.2032 0.3048)
						)
						(arc
							(start 0.2032 0.3048)
							(mid 0.275042 0.275042)
							(end 0.3048 0.2032)
						)
					)
					(width 0)
					(fill yes)
				)
			)
		)
	)
	(footprint ""
		(layer "F.Cu")
		(at 27.5336 -99.1108)
		(property "Reference" "C276"
			(at 0 0 0)
			(layer "F.SilkS")
			(hide yes)
			(effects
				(font
					(size 1.27 1.27)
				)
			)
		)
		(property "Value" "SCD1U16V2KX-3GP"
			(at 1.1811 -2.7051 0)
			(unlocked yes)
			(layer "F.Fab")
			(hide yes)
			(effects
				(font
					(size 1.016 1.016)
					(thickness 0.1524)
				)
			)
		)
		(property "Device Type" "C402H22"
			(at 1.1811 -4.2291 0)
			(unlocked yes)
			(layer "F.Fab")
			(hide yes)
			(effects
				(font
					(size 1.016 1.016)
					(thickness 0.1524)
				)
			)
		)
		(duplicate_pad_numbers_are_jumpers no)
		(fp_rect
			(start -0.4318 0.9525)
			(end 0.4318 -0.9525)
			(stroke
				(width 0)
				(type default)
			)
			(fill no)
			(layer "F.CrtYd")
		)
		(fp_rect
			(start -0.4318 0.9525)
			(end 0.4318 -0.9525)
			(stroke
				(width 0)
				(type default)
			)
			(fill no)
			(layer "F.Fab")
		)
		(pad "1" smd custom
			(at 0 -0.4445)
			(size 0.1524 0.1524)
			(layers "F.Cu" "F.Mask" "F.Paste")
			(net "P3V3_STBY")
			(options
				(clearance outline)
				(anchor circle)
			)
			(primitives
				(gr_poly
					(pts
						(arc
							(start 0.3048 -0.2032)
							(mid 0.275042 -0.275042)
							(end 0.2032 -0.3048)
						)
						(arc
							(start -0.2032 -0.3048)
							(mid -0.275042 -0.275042)
							(end -0.3048 -0.2032)
						)
						(arc
							(start -0.3048 0.2032)
							(mid -0.275042 0.275042)
							(end -0.2032 0.3048)
						)
						(arc
							(start 0.2032 0.3048)
							(mid 0.275042 0.275042)
							(end 0.3048 0.2032)
						)
					)
					(width 0)
					(fill yes)
				)
			)
		)
		(pad "2" smd custom
			(at 0 0.4445)
			(size 0.1524 0.1524)
			(layers "F.Cu" "F.Mask" "F.Paste")
			(net "GND")
			(options
				(clearance outline)
				(anchor circle)
			)
			(primitives
				(gr_poly
					(pts
						(arc
							(start 0.3048 -0.2032)
							(mid 0.275042 -0.275042)
							(end 0.2032 -0.3048)
						)
						(arc
							(start -0.2032 -0.3048)
							(mid -0.275042 -0.275042)
							(end -0.3048 -0.2032)
						)
						(arc
							(start -0.3048 0.2032)
							(mid -0.275042 0.275042)
							(end -0.2032 0.3048)
						)
						(arc
							(start 0.2032 0.3048)
							(mid 0.275042 0.275042)
							(end 0.3048 0.2032)
						)
					)
					(width 0)
					(fill yes)
				)
			)
		)
	)
	(footprint ""
		(layer "F.Cu")
		(at 22.8854 -67.6656 -90)
		(property "Reference" "TP148"
			(at 0 0 270)
			(layer "F.SilkS")
			(hide yes)
			(effects
				(font
					(size 1.27 1.27)
				)
			)
		)
		(property "Value" "TPAD28-2-GP"
			(at -0.0127 -1.6637 270)
			(unlocked yes)
			(layer "F.Fab")
			(hide yes)
			(effects
				(font
					(size 1.016 1.016)
					(thickness 0.1524)
				)
			)
		)
		(property "Device Type" "TPAD28"
			(at -0.0127 -3.1877 270)
			(unlocked yes)
			(layer "F.Fab")
			(hide yes)
			(effects
				(font
					(size 1.016 1.016)
					(thickness 0.1524)
				)
			)
		)
		(duplicate_pad_numbers_are_jumpers no)
		(fp_poly
			(pts
				(arc
					(start 0 -0.3556)
					(mid 0 0.3556)
					(end 0 -0.3556)
				)
			)
			(stroke
				(width 0)
				(type default)
			)
			(fill no)
			(layer "F.CrtYd")
		)
		(fp_poly
			(pts
				(arc
					(start 0 -0.6096)
					(mid 0 0.6096)
					(end 0 -0.6096)
				)
			)
			(stroke
				(width 0)
				(type default)
			)
			(fill no)
			(layer "F.Fab")
		)
		(pad "1" smd circle
			(at 0 0 270)
			(size 0.7112 0.7112)
			(layers "F.Cu" "F.Mask" "F.Paste")
			(net "TP_SDP0")
		)
	)
	(footprint ""
		(layer "F.Cu")
		(at 328.676 -61.849 -90)
		(property "Reference" "PL9"
			(at 0 0 270)
			(layer "F.SilkS")
			(hide yes)
			(effects
				(font
					(size 1.27 1.27)
				)
			)
		)
		(property "Value" "IND-320NH-4-GP"
			(at 7.6454 -3.1115 270)
			(unlocked yes)
			(layer "F.Fab")
			(hide yes)
			(effects
				(font
					(size 1.016 1.016)
					(thickness 0.1524)
				)
			)
		)
		(property "Device Type" "L127126-508254H315"
			(at 7.6454 -4.6355 270)
			(unlocked yes)
			(layer "F.Fab")
			(hide yes)
			(effects
				(font
					(size 1.016 1.016)
					(thickness 0.1524)
				)
			)
		)
		(duplicate_pad_numbers_are_jumpers no)
		(fp_line
			(start -6.604 7.1755)
			(end -6.604 -7.1755)
			(stroke
				(width 0.1524)
				(type default)
			)
			(layer "F.SilkS")
		)
		(fp_line
			(start 6.604 7.1755)
			(end -6.604 7.1755)
			(stroke
				(width 0.1524)
				(type default)
			)
			(layer "F.SilkS")
		)
		(fp_line
			(start -6.604 -7.1755)
			(end 6.604 -7.1755)
			(stroke
				(width 0.1524)
				(type default)
			)
			(layer "F.SilkS")
		)
		(fp_line
			(start 6.604 -7.1755)
			(end 6.604 7.1755)
			(stroke
				(width 0.1524)
				(type default)
			)
			(layer "F.SilkS")
		)
		(fp_rect
			(start -6.35 6.2865)
			(end 6.35 -6.2865)
			(stroke
				(width 0)
				(type default)
			)
			(fill no)
			(layer "F.CrtYd")
		)
		(fp_poly
			(pts
				(xy -6.858 7.2517) (xy -6.858 6.2865) (xy 6.35 6.2865) (xy 6.35 -6.2865) (xy -6.35 -6.2865) (xy -6.35 6.2738)
				(xy -6.858 6.2738) (xy -6.858 -7.2517) (xy 6.858 -7.2517) (xy 6.858 7.2517)
			)
			(stroke
				(width 0)
				(type default)
			)
			(fill no)
			(layer "F.CrtYd")
		)
		(fp_rect
			(start -6.858 7.2517)
			(end 6.858 -7.2517)
			(stroke
				(width 0)
				(type default)
			)
			(fill no)
			(layer "F.Fab")
		)
		(pad "1" smd rect
			(at 0 -5.210556 270)
			(size 5.334 3.429)
			(layers "F.Cu" "F.Mask" "F.Paste")
			(net "P0V9_E_LX")
		)
		(pad "2" smd rect
			(at 0 5.210556 270)
			(size 5.334 3.429)
			(layers "F.Cu" "F.Mask" "F.Paste")
			(net "P0V9_E")
		)
	)
	(footprint ""
		(layer "F.Cu")
		(at 332.772512 -172.432218)
		(property "Reference" "R7924"
			(at 0 0 0)
			(layer "F.SilkS")
			(hide yes)
			(effects
				(font
					(size 1.27 1.27)
				)
			)
		)
		(property "Value" "0R2J-2-GP"
			(at 0.064008 -3.993896 0)
			(unlocked yes)
			(layer "F.Fab")
			(hide yes)
			(effects
				(font
					(size 1.016 1.016)
					(thickness 0.1524)
				)
			)
		)
		(property "Device Type" "R402H16"
			(at 0.064008 -5.517896 0)
			(unlocked yes)
			(layer "F.Fab")
			(hide yes)
			(effects
				(font
					(size 1.016 1.016)
					(thickness 0.1524)
				)
			)
		)
		(duplicate_pad_numbers_are_jumpers no)
		(fp_line
			(start -0.508 -0.9398)
			(end -0.508 0.9398)
			(stroke
				(width 0.1524)
				(type default)
			)
			(layer "F.SilkS")
		)
		(fp_line
			(start 0.508 -0.9398)
			(end -0.508 -0.9398)
			(stroke
				(width 0.1524)
				(type default)
			)
			(layer "F.SilkS")
		)
		(fp_rect
			(start -0.508 0.9398)
			(end 0.508 -0.9398)
			(stroke
				(width 0)
				(type default)
			)
			(fill no)
			(layer "F.CrtYd")
		)
		(fp_rect
			(start -0.508 0.9398)
			(end 0.508 -0.9398)
			(stroke
				(width 0)
				(type default)
			)
			(fill no)
			(layer "F.Fab")
		)
		(pad "1" smd custom
			(at 0 -0.4445)
			(size 0.1397 0.1397)
			(layers "F.Cu" "F.Mask" "F.Paste")
			(net "SSD_PRSNT#4")
			(options
				(clearance outline)
				(anchor circle)
			)
			(primitives
				(gr_poly
					(pts
						(arc
							(start -0.1778 -0.2794)
							(mid -0.249642 -0.249642)
							(end -0.2794 -0.1778)
						)
						(arc
							(start -0.2794 0.1778)
							(mid -0.249642 0.249642)
							(end -0.1778 0.2794)
						)
						(arc
							(start 0.1778 0.2794)
							(mid 0.249642 0.249642)
							(end 0.2794 0.1778)
						)
						(arc
							(start 0.2794 -0.1778)
							(mid 0.249642 -0.249642)
							(end 0.1778 -0.2794)
						)
					)
					(width 0)
					(fill yes)
				)
			)
		)
		(pad "2" smd custom
			(at 0 0.4445)
			(size 0.1397 0.1397)
			(layers "F.Cu" "F.Mask" "F.Paste")
			(net "SSD_PRSNT#4_R")
			(options
				(clearance outline)
				(anchor circle)
			)
			(primitives
				(gr_poly
					(pts
						(arc
							(start -0.1778 -0.2794)
							(mid -0.249642 -0.249642)
							(end -0.2794 -0.1778)
						)
						(arc
							(start -0.2794 0.1778)
							(mid -0.249642 0.249642)
							(end -0.1778 0.2794)
						)
						(arc
							(start 0.1778 0.2794)
							(mid 0.249642 0.249642)
							(end 0.2794 0.1778)
						)
						(arc
							(start 0.2794 -0.1778)
							(mid 0.249642 -0.249642)
							(end 0.1778 -0.2794)
						)
					)
					(width 0)
					(fill yes)
				)
			)
		)
	)
)
